# S9S_MB_2U (Grand Teton) — schematic netlist excerpt (pin names and nets, part order shuffled) for the footprints in the layout excerpt that follows; sources: Cadence DE-HDL packaged netlist, KiCad conversion of 03242023_DA0F0TMBIJ0_F0T_Motherboard_J_brd_V01_OCP.brd

R3728  Q_RES  2.2K 5% CHIP  pkg 0402LF  page 233 : A = P3V3_AUX ; B = SMB_LM75_1_3V3AUX_SDA
C953  Q_CAP_DIFFBUS  DIFF BUS_0.22UF 6.3V 20% X6S  pkg C0201  page 173 : \1\ = P5E_CPU0_PE2_TX_C_DP<6> ; \2\ = P5E_CPU0_PE2_TX_DP<6>
R3279  Q_RES  68K 1% EMPTY  pkg 0402LF  page 166 : A = FM_P2E_EQB1 ; B = GND

(kicad_pcb
	(version 20260206)
	(generator "pcbnew")
	(generator_version "10.0")
	(general
		(thickness 1.6)
		(legacy_teardrops no)
	)
	(paper "A4")
	(title_block
		(title "03242023_DA0F0TMBIJ0_F0T_Motherboard_J_brd_V01_OCP.brd")
		(comment 1 "Grand Teton / footprints 2818-2820 of 6105")
	)
	(layers
		(0 "F.Cu" signal "TOP")
		(4 "In1.Cu" signal "GND")
		(6 "In2.Cu" signal "IN1")
		(8 "In3.Cu" signal "GND1")
		(10 "In4.Cu" signal "IN2")
		(12 "In5.Cu" signal "GND2")
		(14 "In6.Cu" signal "IN3")
		(16 "In7.Cu" signal "GND3")
		(18 "In8.Cu" signal "VCC")
		(20 "In9.Cu" signal "VCC1")
		(22 "In10.Cu" signal "GND4")
		(24 "In11.Cu" signal "IN4")
		(26 "In12.Cu" signal "GND5")
		(28 "In13.Cu" signal "IN5")
		(30 "In14.Cu" signal "GND6")
		(32 "In15.Cu" signal "IN6")
		(34 "In16.Cu" signal "GND7")
		(2 "B.Cu" signal "BOTTOM")
		(9 "F.Adhes" user "F.Adhesive")
		(11 "B.Adhes" user "B.Adhesive")
		(13 "F.Paste" user "Package Geometry/Pastemask Top")
		(15 "B.Paste" user "Package Geometry/Pastemask Bottom")
		(5 "F.SilkS" user "Ref Des/Silkscreen Top")
		(7 "B.SilkS" user "Ref Des/Silkscreen Bottom")
		(1 "F.Mask" user "Board Geometry/Soldermask Top")
		(3 "B.Mask" user "Board Geometry/Soldermask Bottom")
		(17 "Dwgs.User" user "User.Drawings")
		(19 "Cmts.User" user "User.Comments")
		(21 "Eco1.User" user "User.Eco1")
		(23 "Eco2.User" user "User.Eco2")
		(25 "Edge.Cuts" user "Board Geometry/Outline")
		(27 "Margin" user)
		(31 "F.CrtYd" user "Package Geometry/Place Bound Top")
		(29 "B.CrtYd" user "Package Geometry/Place Bound Bottom")
		(35 "F.Fab" user "Ref Des/Assembly Top")
		(33 "B.Fab" user "Ref Des/Assembly Bottom")
	)
	(footprint ""
		(layer "F.Cu")
		(at 27.628596 -397.406876)
		(property "Reference" "R3279"
			(at 0 0 0)
			(layer "F.SilkS")
			(hide yes)
			(effects
				(font
					(size 1.27 1.27)
				)
			)
		)
		(property "Value" ""
			(at 0 0 0)
			(layer "F.Fab")
			(effects
				(font
					(size 1.27 1.27)
				)
			)
		)
		(duplicate_pad_numbers_are_jumpers no)
		(fp_line
			(start -0.7874 -0.4064)
			(end 0.7874 -0.4064)
			(stroke
				(width 0.1524)
				(type default)
			)
			(layer "F.SilkS")
		)
		(fp_line
			(start -0.7874 0.4064)
			(end -0.7874 -0.4064)
			(stroke
				(width 0.1524)
				(type default)
			)
			(layer "F.SilkS")
		)
		(fp_line
			(start 0.7874 -0.4064)
			(end 0.7874 0.4064)
			(stroke
				(width 0.1524)
				(type default)
			)
			(layer "F.SilkS")
		)
		(fp_line
			(start 0.7874 0.4064)
			(end -0.7874 0.4064)
			(stroke
				(width 0.1524)
				(type default)
			)
			(layer "F.SilkS")
		)
		(fp_line
			(start -0.67945 -0.305054)
			(end -0.12065 -0.305054)
			(stroke
				(width 0.1)
				(type default)
			)
			(layer "F.Fab")
		)
		(fp_line
			(start -0.67945 0.3048)
			(end -0.67945 -0.305054)
			(stroke
				(width 0.1)
				(type default)
			)
			(layer "F.Fab")
		)
		(fp_line
			(start -0.12065 -0.305054)
			(end -0.12065 -0.2794)
			(stroke
				(width 0.1)
				(type default)
			)
			(layer "F.Fab")
		)
		(fp_line
			(start -0.12065 -0.2794)
			(end 0.12065 -0.2794)
			(stroke
				(width 0.1)
				(type default)
			)
			(layer "F.Fab")
		)
		(fp_line
			(start -0.12065 0.2794)
			(end -0.12065 0.3048)
			(stroke
				(width 0.1)
				(type default)
			)
			(layer "F.Fab")
		)
		(fp_line
			(start -0.12065 0.3048)
			(end -0.67945 0.3048)
			(stroke
				(width 0.1)
				(type default)
			)
			(layer "F.Fab")
		)
		(fp_line
			(start 0.120396 0.2794)
			(end -0.12065 0.2794)
			(stroke
				(width 0.1)
				(type default)
			)
			(layer "F.Fab")
		)
		(fp_line
			(start 0.120396 0.3048)
			(end 0.120396 0.2794)
			(stroke
				(width 0.1)
				(type default)
			)
			(layer "F.Fab")
		)
		(fp_line
			(start 0.12065 -0.3048)
			(end 0.67945 -0.3048)
			(stroke
				(width 0.1)
				(type default)
			)
			(layer "F.Fab")
		)
		(fp_line
			(start 0.12065 -0.2794)
			(end 0.12065 -0.3048)
			(stroke
				(width 0.1)
				(type default)
			)
			(layer "F.Fab")
		)
		(fp_line
			(start 0.67945 -0.3048)
			(end 0.67945 0.3048)
			(stroke
				(width 0.1)
				(type default)
			)
			(layer "F.Fab")
		)
		(fp_line
			(start 0.67945 0.3048)
			(end 0.120396 0.3048)
			(stroke
				(width 0.1)
				(type default)
			)
			(layer "F.Fab")
		)
		(pad "1" smd circle
			(at -0.40005 0)
			(size 0 0)
			(layers "F.Cu" "F.Mask" "F.Paste")
			(net "FM_P2E_EQB1")
		)
		(pad "2" smd circle
			(at 0.40005 0)
			(size 0 0)
			(layers "F.Cu" "F.Mask" "F.Paste")
			(net "GND")
		)
	)
	(footprint ""
		(layer "F.Cu")
		(at 398.96669 -402.371052 -90)
		(property "Reference" "C953"
			(at 0 0 270)
			(layer "F.SilkS")
			(hide yes)
			(effects
				(font
					(size 1.27 1.27)
				)
			)
		)
		(property "Value" ""
			(at 0 0 270)
			(layer "F.Fab")
			(effects
				(font
					(size 1.27 1.27)
				)
			)
		)
		(duplicate_pad_numbers_are_jumpers no)
		(fp_line
			(start -0.299974 0.150114)
			(end -0.299974 -0.150114)
			(stroke
				(width 0.1)
				(type default)
			)
			(layer "F.Fab")
		)
		(fp_line
			(start 0.299974 0.150114)
			(end -0.299974 0.150114)
			(stroke
				(width 0.1)
				(type default)
			)
			(layer "F.Fab")
		)
		(fp_line
			(start -0.299974 -0.150114)
			(end 0.299974 -0.150114)
			(stroke
				(width 0.1)
				(type default)
			)
			(layer "F.Fab")
		)
		(fp_line
			(start 0.299974 -0.150114)
			(end 0.299974 0.150114)
			(stroke
				(width 0.1)
				(type default)
			)
			(layer "F.Fab")
		)
		(pad "1" smd rect
			(at -0.2667 0 270)
			(size 0.3048 0.381)
			(layers "F.Cu" "F.Mask" "F.Paste")
			(net "P5E_CPU0_PE2_TX_C_DP<6>")
		)
		(pad "2" smd rect
			(at 0.2667 0 270)
			(size 0.3048 0.381)
			(layers "F.Cu" "F.Mask" "F.Paste")
			(net "P5E_CPU0_PE2_TX_DP<6>")
		)
	)
	(footprint ""
		(layer "F.Cu")
		(at 51.593496 -109.53877)
		(property "Reference" "R3728"
			(at 0 0 0)
			(layer "F.SilkS")
			(hide yes)
			(effects
				(font
					(size 1.27 1.27)
				)
			)
		)
		(property "Value" ""
			(at 0 0 0)
			(layer "F.Fab")
			(effects
				(font
					(size 1.27 1.27)
				)
			)
		)
		(duplicate_pad_numbers_are_jumpers no)
		(fp_line
			(start -0.7874 -0.4064)
			(end 0.7874 -0.4064)
			(stroke
				(width 0.1524)
				(type default)
			)
			(layer "F.SilkS")
		)
		(fp_line
			(start -0.7874 0.4064)
			(end -0.7874 -0.4064)
			(stroke
				(width 0.1524)
				(type default)
			)
			(layer "F.SilkS")
		)
		(fp_line
			(start 0.7874 -0.4064)
			(end 0.7874 0.4064)
			(stroke
				(width 0.1524)
				(type default)
			)
			(layer "F.SilkS")
		)
		(fp_line
			(start 0.7874 0.4064)
			(end -0.7874 0.4064)
			(stroke
				(width 0.1524)
				(type default)
			)
			(layer "F.SilkS")
		)
		(fp_line
			(start -0.67945 -0.305054)
			(end -0.12065 -0.305054)
			(stroke
				(width 0.1)
				(type default)
			)
			(layer "F.Fab")
		)
		(fp_line
			(start -0.67945 0.3048)
			(end -0.67945 -0.305054)
			(stroke
				(width 0.1)
				(type default)
			)
			(layer "F.Fab")
		)
		(fp_line
			(start -0.12065 -0.305054)
			(end -0.12065 -0.2794)
			(stroke
				(width 0.1)
				(type default)
			)
			(layer "F.Fab")
		)
		(fp_line
			(start -0.12065 -0.2794)
			(end 0.12065 -0.2794)
			(stroke
				(width 0.1)
				(type default)
			)
			(layer "F.Fab")
		)
		(fp_line
			(start -0.12065 0.2794)
			(end -0.12065 0.3048)
			(stroke
				(width 0.1)
				(type default)
			)
			(layer "F.Fab")
		)
		(fp_line
			(start -0.12065 0.3048)
			(end -0.67945 0.3048)
			(stroke
				(width 0.1)
				(type default)
			)
			(layer "F.Fab")
		)
		(fp_line
			(start 0.120396 0.2794)
			(end -0.12065 0.2794)
			(stroke
				(width 0.1)
				(type default)
			)
			(layer "F.Fab")
		)
		(fp_line
			(start 0.120396 0.3048)
			(end 0.120396 0.2794)
			(stroke
				(width 0.1)
				(type default)
			)
			(layer "F.Fab")
		)
		(fp_line
			(start 0.12065 -0.3048)
			(end 0.67945 -0.3048)
			(stroke
				(width 0.1)
				(type default)
			)
			(layer "F.Fab")
		)
		(fp_line
			(start 0.12065 -0.2794)
			(end 0.12065 -0.3048)
			(stroke
				(width 0.1)
				(type default)
			)
			(layer "F.Fab")
		)
		(fp_line
			(start 0.67945 -0.3048)
			(end 0.67945 0.3048)
			(stroke
				(width 0.1)
				(type default)
			)
			(layer "F.Fab")
		)
		(fp_line
			(start 0.67945 0.3048)
			(end 0.120396 0.3048)
			(stroke
				(width 0.1)
				(type default)
			)
			(layer "F.Fab")
		)
		(pad "1" smd circle
			(at -0.40005 0)
			(size 0 0)
			(layers "F.Cu" "F.Mask" "F.Paste")
			(net "P3V3_AUX")
		)
		(pad "2" smd circle
			(at 0.40005 0)
			(size 0 0)
			(layers "F.Cu" "F.Mask" "F.Paste")
			(net "SMB_LM75_1_3V3AUX_SDA")
		)
	)
)
